(kicad_pcb
	(version 20260206)
	(generator "pcbnew")
	(generator_version "10.0")
	(general
		(thickness 1.6)
		(legacy_teardrops no)
	)
	(paper "A4")
	(title_block
		(title "dpb — 14545-sa.0730WZS0815.brd")
		(comment 1 "Honey Badger (Wiwynn) / footprints 249-250 of 1066")
	)
	(layers
		(0 "F.Cu" signal "TOP")
		(4 "In1.Cu" signal "L2GND")
		(6 "In2.Cu" signal "L3")
		(8 "In3.Cu" signal "L4VCC")
		(10 "In4.Cu" signal "L5VCC")
		(12 "In5.Cu" signal "L6")
		(14 "In6.Cu" signal "L7GND")
		(2 "B.Cu" signal "BOTTOM")
		(9 "F.Adhes" user "F.Adhesive")
		(11 "B.Adhes" user "B.Adhesive")
		(13 "F.Paste" user "Package Geometry/Pastemask Top")
		(15 "B.Paste" user "Package Geometry/Pastemask Bottom")
		(5 "F.SilkS" user "Ref Des/Silkscreen Top")
		(7 "B.SilkS" user "Ref Des/Silkscreen Bottom")
		(1 "F.Mask" user "Board Geometry/Soldermask Top")
		(3 "B.Mask" user "Board Geometry/Soldermask Bottom")
		(17 "Dwgs.User" user "User.Drawings")
		(19 "Cmts.User" user "User.Comments")
		(21 "Eco1.User" user "User.Eco1")
		(23 "Eco2.User" user "User.Eco2")
		(25 "Edge.Cuts" user "Board Geometry/Outline")
		(27 "Margin" user)
		(31 "F.CrtYd" user "Package Geometry/Place Bound Top")
		(29 "B.CrtYd" user "Package Geometry/Place Bound Bottom")
		(35 "F.Fab" user "Ref Des/Assembly Top")
		(33 "B.Fab" user "Ref Des/Assembly Bottom")
	)
	(footprint ""
		(layer "F.Cu")
		(at 17.500092 -335.330038 -90)
		(property "Reference" "SKT12"
			(at 0 0 270)
			(layer "F.SilkS")
			(hide yes)
			(effects
				(font
					(size 1.27 1.27)
				)
			)
		)
		(property "Value" "SKT-SATA14P-15P-12-GP"
			(at -22.6187 8.1788 270)
			(unlocked yes)
			(layer "F.Fab")
			(hide yes)
			(effects
				(font
					(size 1.016 1.016)
					(thickness 0.1524)
				)
			)
		)
		(property "Device Type" "87945-1001"
			(at -22.6187 6.6548 270)
			(unlocked yes)
			(layer "F.Fab")
			(hide yes)
			(effects
				(font
					(size 1.016 1.016)
					(thickness 0.1524)
				)
			)
		)
		(duplicate_pad_numbers_are_jumpers no)
		(fp_line
			(start -20.4724 9.652)
			(end -20.4724 2.3114)
			(stroke
				(width 0.1524)
				(type default)
			)
			(layer "F.SilkS")
		)
		(fp_line
			(start -17.8435 9.652)
			(end -20.4724 9.652)
			(stroke
				(width 0.1524)
				(type default)
			)
			(layer "F.SilkS")
		)
		(fp_line
			(start 17.8435 9.652)
			(end 17.8435 7.9502)
			(stroke
				(width 0.1524)
				(type default)
			)
			(layer "F.SilkS")
		)
		(fp_line
			(start 20.4724 9.652)
			(end 17.8435 9.652)
			(stroke
				(width 0.1524)
				(type default)
			)
			(layer "F.SilkS")
		)
		(fp_line
			(start -17.8435 7.9502)
			(end -17.8435 9.652)
			(stroke
				(width 0.1524)
				(type default)
			)
			(layer "F.SilkS")
		)
		(fp_line
			(start 17.8435 7.9502)
			(end -17.8435 7.9502)
			(stroke
				(width 0.1524)
				(type default)
			)
			(layer "F.SilkS")
		)
		(fp_line
			(start -23.7617 2.3114)
			(end -23.7617 -2.3114)
			(stroke
				(width 0.1524)
				(type default)
			)
			(layer "F.SilkS")
		)
		(fp_line
			(start -20.4724 2.3114)
			(end -23.7617 2.3114)
			(stroke
				(width 0.1524)
				(type default)
			)
			(layer "F.SilkS")
		)
		(fp_line
			(start 20.4724 2.3114)
			(end 20.4724 9.652)
			(stroke
				(width 0.1524)
				(type default)
			)
			(layer "F.SilkS")
		)
		(fp_line
			(start 23.7617 2.3114)
			(end 20.4724 2.3114)
			(stroke
				(width 0.1524)
				(type default)
			)
			(layer "F.SilkS")
		)
		(fp_line
			(start -23.117556 0.5461)
			(end -23.117556 -0.5461)
			(stroke
				(width 0.3048)
				(type default)
			)
			(layer "F.SilkS")
		)
		(fp_line
			(start 20.882356 0.5461)
			(end 20.882356 -0.5461)
			(stroke
				(width 0.3048)
				(type default)
			)
			(layer "F.SilkS")
		)
		(fp_line
			(start -20.882356 -0.5461)
			(end -20.882356 0.5461)
			(stroke
				(width 0.3048)
				(type default)
			)
			(layer "F.SilkS")
		)
		(fp_line
			(start 23.117556 -0.5461)
			(end 23.117556 0.5461)
			(stroke
				(width 0.3048)
				(type default)
			)
			(layer "F.SilkS")
		)
		(fp_line
			(start -23.7617 -2.3114)
			(end -20.4724 -2.3114)
			(stroke
				(width 0.1524)
				(type default)
			)
			(layer "F.SilkS")
		)
		(fp_line
			(start -20.4724 -2.3114)
			(end -20.4724 -5.7658)
			(stroke
				(width 0.1524)
				(type default)
			)
			(layer "F.SilkS")
		)
		(fp_line
			(start 20.4724 -2.3114)
			(end 23.7617 -2.3114)
			(stroke
				(width 0.1524)
				(type default)
			)
			(layer "F.SilkS")
		)
		(fp_line
			(start 23.7617 -2.3114)
			(end 23.7617 2.3114)
			(stroke
				(width 0.1524)
				(type default)
			)
			(layer "F.SilkS")
		)
		(fp_line
			(start -20.4724 -5.7658)
			(end 20.4724 -5.7658)
			(stroke
				(width 0.1524)
				(type default)
			)
			(layer "F.SilkS")
		)
		(fp_line
			(start 20.4724 -5.7658)
			(end 20.4724 -2.3114)
			(stroke
				(width 0.1524)
				(type default)
			)
			(layer "F.SilkS")
		)
		(fp_line
			(start -15.3924 -5.8547)
			(end -16.3576 -5.8547)
			(stroke
				(width 0.3302)
				(type default)
			)
			(layer "F.SilkS")
		)
		(fp_arc
			(start -20.882356 0.5461)
			(mid -21.999956 1.6637)
			(end -23.117556 0.5461)
			(stroke
				(width 0.3048)
				(type default)
			)
			(layer "F.SilkS")
		)
		(fp_arc
			(start 23.117556 0.5461)
			(mid 21.999956 1.6637)
			(end 20.882356 0.5461)
			(stroke
				(width 0.3048)
				(type default)
			)
			(layer "F.SilkS")
		)
		(fp_arc
			(start -23.117556 -0.5461)
			(mid -21.999956 -1.6637)
			(end -20.882356 -0.5461)
			(stroke
				(width 0.3048)
				(type default)
			)
			(layer "F.SilkS")
		)
		(fp_arc
			(start 20.882356 -0.5461)
			(mid 21.999956 -1.6637)
			(end 23.117556 -0.5461)
			(stroke
				(width 0.3048)
				(type default)
			)
			(layer "F.SilkS")
		)
		(fp_poly
			(pts
				(xy -15.87119 -5.838698) (xy -15.23619 -6.473698) (xy -16.50619 -6.473698)
			)
			(stroke
				(width 0)
				(type default)
			)
			(fill yes)
			(layer "F.SilkS")
		)
		(fp_poly
			(pts
				(xy -20.2184 -5.5118) (xy 20.2184 -5.5118) (xy 20.2184 -2.0574) (xy 23.5077 -2.0574) (xy 23.5077 2.0574)
				(xy 20.2184 2.0574) (xy 20.2184 9.398) (xy 18.0975 9.398) (xy 18.0975 7.6962) (xy -18.0975 7.6962)
				(xy -18.0975 9.398) (xy -20.2184 9.398) (xy -20.2184 2.0574) (xy -23.5077 2.0574) (xy -23.5077 -2.0574)
				(xy -20.2184 -2.0574)
			)
			(stroke
				(width 0)
				(type default)
			)
			(fill no)
			(layer "F.CrtYd")
		)
		(fp_poly
			(pts
				(xy -20.2184 -5.5118) (xy -20.2184 -6.0198) (xy -20.7264 -6.0198) (xy -20.7264 -2.5654) (xy -24.0157 -2.5654)
				(xy -24.0157 2.5654) (xy -20.7264 2.5654) (xy -20.7264 9.906) (xy -17.5895 9.906) (xy -17.5895 8.2042)
				(xy 17.5895 8.2042) (xy 17.5895 9.906) (xy 20.7264 9.906) (xy 20.7264 2.5654) (xy 24.0157 2.5654)
				(xy 24.0157 -2.5654) (xy 20.7264 -2.5654) (xy 20.7264 -6.0198) (xy -20.21586 -6.0198) (xy -20.21586 -5.5118)
				(xy 20.2184 -5.5118) (xy 20.2184 -2.0574) (xy 23.5077 -2.0574) (xy 23.5077 2.0574) (xy 20.2184 2.0574)
				(xy 20.2184 9.398) (xy 18.0975 9.398) (xy 18.0975 7.6962) (xy -18.0975 7.6962) (xy -18.0975 9.398)
				(xy -20.2184 9.398) (xy -20.2184 2.0574) (xy -23.5077 2.0574) (xy -23.5077 -2.0574) (xy -20.2184 -2.0574)
			)
			(stroke
				(width 0)
				(type default)
			)
			(fill no)
			(layer "F.CrtYd")
		)
		(fp_poly
			(pts
				(xy -20.7264 -6.0198) (xy -20.7264 -2.5654) (xy -24.0157 -2.5654) (xy -24.0157 2.5654) (xy -20.7264 2.5654)
				(xy -20.7264 9.906) (xy -17.5895 9.906) (xy -17.5895 8.2042) (xy 17.5895 8.2042) (xy 17.5895 9.906)
				(xy 20.7264 9.906) (xy 20.7264 2.5654) (xy 24.0157 2.5654) (xy 24.0157 -2.5654) (xy 20.7264 -2.5654)
				(xy 20.7264 -6.0198)
			)
			(stroke
				(width 0)
				(type default)
			)
			(fill no)
			(layer "F.Fab")
		)
		(pad "" np_thru_hole circle
			(at -18.999962 -2.350008 270)
			(size 0.254 0.254)
			(drill 1.8542)
			(layers "*.Cu" "*.Mask")
			(clearance 1.1557)
			(thermal_gap 1.1557)
		)
		(pad "" np_thru_hole circle
			(at 18.999962 -2.350008 270)
			(size 0.254 0.254)
			(drill 1.8542)
			(layers "*.Cu" "*.Mask")
			(clearance 1.1557)
			(thermal_gap 1.1557)
		)
		(pad "H1" thru_hole oval
			(at -21.999956 0 270)
			(size 1.524 2.6162)
			(drill oval 0.8128 1.905)
			(layers "*.Cu" "*.Mask")
			(remove_unused_layers no)
			(net "GND")
			(clearance 0.1524)
			(thermal_gap 0.1524)
		)
		(pad "H2" thru_hole oval
			(at 21.999956 0 270)
			(size 1.524 2.6162)
			(drill oval 0.8128 1.905)
			(layers "*.Cu" "*.Mask")
			(remove_unused_layers no)
			(net "GND")
			(clearance 0.1524)
			(thermal_gap 0.1524)
		)
		(pad "P1" smd rect
			(at -1.89992 -4.249928 270)
			(size 0.6604 2.3876)
			(layers "F.Cu" "F.Mask" "F.Paste")
			(net "Net_60")
		)
		(pad "P2" smd rect
			(at -0.62992 -4.249928 270)
			(size 0.6604 2.3876)
			(layers "F.Cu" "F.Mask" "F.Paste")
			(net "Net_59")
		)
		(pad "P3" smd rect
			(at 0.64008 -4.249928 270)
			(size 0.6604 2.3876)
			(layers "F.Cu" "F.Mask" "F.Paste")
			(net "Net_58")
		)
		(pad "P4" smd rect
			(at 1.91008 -4.249928 270)
			(size 0.6604 2.3876)
			(layers "F.Cu" "F.Mask" "F.Paste")
			(net "GND")
		)
		(pad "P5" smd rect
			(at 3.18008 -4.249928 270)
			(size 0.6604 2.3876)
			(layers "F.Cu" "F.Mask" "F.Paste")
			(net "HDD_PRSNT_NET11")
		)
		(pad "P6" smd rect
			(at 4.45008 -4.249928 270)
			(size 0.6604 2.3876)
			(layers "F.Cu" "F.Mask" "F.Paste")
			(net "GND")
		)
		(pad "P7" smd rect
			(at 5.72008 -4.249928 270)
			(size 0.6604 2.3876)
			(layers "F.Cu" "F.Mask" "F.Paste")
			(net "5V_PRE_11")
		)
		(pad "P8" smd rect
			(at 6.99008 -4.249928 270)
			(size 0.6604 2.3876)
			(layers "F.Cu" "F.Mask" "F.Paste")
			(net "P5V_HDD11")
		)
		(pad "P9" smd rect
			(at 8.26008 -4.249928 270)
			(size 0.6604 2.3876)
			(layers "F.Cu" "F.Mask" "F.Paste")
			(net "P5V_HDD11")
		)
		(pad "P10" smd rect
			(at 9.53008 -4.249928 270)
			(size 0.6604 2.3876)
			(layers "F.Cu" "F.Mask" "F.Paste")
			(net "GND")
		)
		(pad "P11" smd rect
			(at 10.80008 -4.249928 270)
			(size 0.6604 2.3876)
			(layers "F.Cu" "F.Mask" "F.Paste")
			(net "ACT_HDD11")
		)
		(pad "P12" smd rect
			(at 12.07008 -4.249928 270)
			(size 0.6604 2.3876)
			(layers "F.Cu" "F.Mask" "F.Paste")
			(net "GND")
		)
		(pad "P13" smd rect
			(at 13.34008 -4.249928 270)
			(size 0.6604 2.3876)
			(layers "F.Cu" "F.Mask" "F.Paste")
			(net "12V_PRE_11")
		)
		(pad "P14" smd rect
			(at 14.61008 -4.249928 270)
			(size 0.6604 2.3876)
			(layers "F.Cu" "F.Mask" "F.Paste")
			(net "P12V_HDD11")
		)
		(pad "P15" smd rect
			(at 15.88008 -4.249928 270)
			(size 0.6604 2.3876)
			(layers "F.Cu" "F.Mask" "F.Paste")
			(net "P12V_HDD11")
		)
		(pad "S1" smd rect
			(at -15.86992 -4.249928 270)
			(size 0.6604 2.3876)
			(layers "F.Cu" "F.Mask" "F.Paste")
			(net "GND")
		)
		(pad "S2" smd rect
			(at -14.59992 -4.249928 270)
			(size 0.6604 2.3876)
			(layers "F.Cu" "F.Mask" "F.Paste")
			(net "SAS2X28_A_HDD11_TX_+")
		)
		(pad "S3" smd rect
			(at -13.32992 -4.249928 270)
			(size 0.6604 2.3876)
			(layers "F.Cu" "F.Mask" "F.Paste")
			(net "SAS2X28_A_HDD11_TX_-")
		)
		(pad "S4" smd rect
			(at -12.05992 -4.249928 270)
			(size 0.6604 2.3876)
			(layers "F.Cu" "F.Mask" "F.Paste")
			(net "GND")
		)
		(pad "S5" smd rect
			(at -10.78992 -4.249928 270)
			(size 0.6604 2.3876)
			(layers "F.Cu" "F.Mask" "F.Paste")
			(net "SAS2X28_DRIVE_RX_N_A11")
		)
		(pad "S6" smd rect
			(at -9.51992 -4.249928 270)
			(size 0.6604 2.3876)
			(layers "F.Cu" "F.Mask" "F.Paste")
			(net "SAS2X28_DRIVE_RX_P_A11")
		)
		(pad "S7" smd rect
			(at -8.24992 -4.249928 270)
			(size 0.6604 2.3876)
			(layers "F.Cu" "F.Mask" "F.Paste")
			(net "GND")
		)
		(pad "S8" smd rect
			(at -7.480046 -2.100072 270)
			(size 0.508 1.905)
			(layers "F.Cu" "F.Mask" "F.Paste")
			(net "GND")
		)
		(pad "S9" smd rect
			(at -6.679946 -2.100072 270)
			(size 0.508 1.905)
			(layers "F.Cu" "F.Mask" "F.Paste")
			(net "SAS2X28_B_HDD11_TX_+")
		)
		(pad "S10" smd rect
			(at -5.8801 -2.100072 270)
			(size 0.508 1.905)
			(layers "F.Cu" "F.Mask" "F.Paste")
			(net "SAS2X28_B_HDD11_TX_-")
		)
		(pad "S11" smd rect
			(at -5.08 -2.100072 270)
			(size 0.508 1.905)
			(layers "F.Cu" "F.Mask" "F.Paste")
			(net "GND")
		)
		(pad "S12" smd rect
			(at -4.2799 -2.100072 270)
			(size 0.508 1.905)
			(layers "F.Cu" "F.Mask" "F.Paste")
			(net "SAS2X28_DRIVE_RX_N_B11")
		)
		(pad "S13" smd rect
			(at -3.480054 -2.100072 270)
			(size 0.508 1.905)
			(layers "F.Cu" "F.Mask" "F.Paste")
			(net "SAS2X28_DRIVE_RX_P_B11")
		)
		(pad "S14" smd rect
			(at -2.679954 -2.100072 270)
			(size 0.508 1.905)
			(layers "F.Cu" "F.Mask" "F.Paste")
			(net "GND")
		)
		(zone
			(layers "F.Cu" "B.Cu" "In1.Cu" "In2.Cu" "In3.Cu" "In4.Cu" "In5.Cu" "In6.Cu")
			(hatch none 0.5)
			(connect_pads
				(clearance 0)
			)
			(min_thickness 0.25)
			(keepout
				(tracks not_allowed)
				(vias allowed)
				(pads allowed)
				(copperpour not_allowed)
				(footprints allowed)
			)
			(placement
				(enabled no)
				(sheetname "")
			)
			(fill
				(thermal_gap 0.5)
				(thermal_bridge_width 0.5)
				(island_removal_mode 0)
			)
			(polygon
				(pts
					(arc
						(start 21.082 -354.33)
						(mid 18.6182 -354.33)
						(end 21.082 -354.33)
					)
				)
			)
		)
		(zone
			(layers "F.Cu" "B.Cu" "In1.Cu" "In2.Cu" "In3.Cu" "In4.Cu" "In5.Cu" "In6.Cu")
			(hatch none 0.5)
			(connect_pads
				(clearance 0)
			)
			(min_thickness 0.25)
			(keepout
				(tracks not_allowed)
				(vias allowed)
				(pads allowed)
				(copperpour not_allowed)
				(footprints allowed)
			)
			(placement
				(enabled no)
				(sheetname "")
			)
			(fill
				(thermal_gap 0.5)
				(thermal_bridge_width 0.5)
				(island_removal_mode 0)
			)
			(polygon
				(pts
					(arc
						(start 21.082 -316.330076)
						(mid 18.6182 -316.330076)
						(end 21.082 -316.330076)
					)
				)
			)
		)
	)
	(footprint ""
		(layer "F.Cu")
		(at 205.953614 -281.613864 90)
		(property "Reference" "Q5"
			(at 0 0 90)
			(layer "F.SilkS")
			(hide yes)
			(effects
				(font
					(size 1.27 1.27)
				)
			)
		)
		(property "Value" "AO4406AL-GP"
			(at -3.707384 -1.5367 90)
			(unlocked yes)
			(layer "F.Fab")
			(hide yes)
			(effects
				(font
					(size 1.016 1.016)
					(thickness 0.1524)
				)
			)
		)
		(property "Device Type" "SOIC8H69"
			(at -3.707384 -3.0607 90)
			(unlocked yes)
			(layer "F.Fab")
			(hide yes)
			(effects
				(font
					(size 1.016 1.016)
					(thickness 0.1524)
				)
			)
		)
		(duplicate_pad_numbers_are_jumpers no)
		(fp_line
			(start 2.1336 -1.4224)
			(end -2.7432 -1.4224)
			(stroke
				(width 0.1524)
				(type default)
			)
			(layer "F.SilkS")
		)
		(fp_line
			(start -2.7432 -1.4224)
			(end -2.7432 1.4224)
			(stroke
				(width 0.1524)
				(type default)
			)
			(layer "F.SilkS")
		)
		(fp_line
			(start -2.7178 -0.508)
			(end -2.1844 -0.0508)
			(stroke
				(width 0.1524)
				(type default)
			)
			(layer "F.SilkS")
		)
		(fp_line
			(start -2.1844 -0.0508)
			(end -2.7178 0.508)
			(stroke
				(width 0.1524)
				(type default)
			)
			(layer "F.SilkS")
		)
		(fp_line
			(start 2.1336 1.4224)
			(end 2.1336 -1.4224)
			(stroke
				(width 0.1524)
				(type default)
			)
			(layer "F.SilkS")
		)
		(fp_line
			(start -2.7432 1.4224)
			(end 2.1336 1.4224)
			(stroke
				(width 0.1524)
				(type default)
			)
			(layer "F.SilkS")
		)
		(fp_line
			(start -2.7432 1.4224)
			(end -2.6416 1.4224)
			(stroke
				(width 0.1524)
				(type default)
			)
			(layer "F.SilkS")
		)
		(fp_line
			(start -2.6289 3.4417)
			(end -2.6289 1.4732)
			(stroke
				(width 0.381)
				(type default)
			)
			(layer "F.SilkS")
		)
		(fp_poly
			(pts
				(xy -2.2098 -1.4224) (xy -2.2098 1.4224) (xy 2.2098 1.4224) (xy 2.2098 -1.4224)
			)
			(stroke
				(width 0)
				(type default)
			)
			(fill yes)
			(layer "F.SilkS")
		)
		(fp_rect
			(start -2.450084 2.999994)
			(end 2.450084 -2.999994)
			(stroke
				(width 0)
				(type default)
			)
			(fill no)
			(layer "F.CrtYd")
		)
		(fp_poly
			(pts
				(xy -2.8194 3.6322) (xy -2.8194 -3.6322) (xy 2.8194 -3.6322) (xy 2.8194 1.18364) (xy 2.450084 1.18364)
				(xy 2.450084 -2.999994) (xy -2.450084 -2.999994) (xy -2.450084 2.999994) (xy 2.450084 2.999994)
				(xy 2.450084 1.18618) (xy 2.8194 1.18618) (xy 2.8194 3.6322)
			)
			(stroke
				(width 0)
				(type default)
			)
			(fill no)
			(layer "F.CrtYd")
		)
		(fp_rect
			(start -2.8194 3.6322)
			(end 2.8194 -3.6322)
			(stroke
				(width 0)
				(type default)
			)
			(fill no)
			(layer "F.Fab")
		)
		(pad "1" smd rect
			(at -1.905 2.54 90)
			(size 0.635 1.651)
			(layers "F.Cu" "F.Mask" "F.Paste")
			(net "P5V_HDD2")
		)
		(pad "2" smd rect
			(at -0.635 2.54 90)
			(size 0.635 1.651)
			(layers "F.Cu" "F.Mask" "F.Paste")
			(net "P5V_HDD2")
		)
		(pad "3" smd rect
			(at 0.635 2.54 90)
			(size 0.635 1.651)
			(layers "F.Cu" "F.Mask" "F.Paste")
			(net "P5V_HDD2")
		)
		(pad "4" smd rect
			(at 1.905 2.54 90)
			(size 0.635 1.651)
			(layers "F.Cu" "F.Mask" "F.Paste")
			(net "SW_HDD2_P")
		)
		(pad "5" smd rect
			(at 1.905 -2.54 90)
			(size 0.635 1.651)
			(layers "F.Cu" "F.Mask" "F.Paste")
			(net "P5VA")
		)
		(pad "6" smd rect
			(at 0.635 -2.54 90)
			(size 0.635 1.651)
			(layers "F.Cu" "F.Mask" "F.Paste")
			(net "P5VA")
		)
		(pad "7" smd rect
			(at -0.635 -2.54 90)
			(size 0.635 1.651)
			(layers "F.Cu" "F.Mask" "F.Paste")
			(net "P5VA")
		)
		(pad "8" smd rect
			(at -1.905 -2.54 90)
			(size 0.635 1.651)
			(layers "F.Cu" "F.Mask" "F.Paste")
			(net "P5VA")
		)
	)
)
